(kicad_pcb
	(version 20260206)
	(generator "pcbnew")
	(generator_version "10.0")
	(general
		(thickness 1.6)
		(legacy_teardrops no)
	)
	(paper "A4")
	(title_block
		(title "03242023_DA0F0TMBIJ0_F0T_Motherboard_J_brd_V01_OCP.brd")
		(comment 1 "Grand Teton / footprints 1327-1332 of 6105")
	)
	(layers
		(0 "F.Cu" signal "TOP")
		(4 "In1.Cu" signal "GND")
		(6 "In2.Cu" signal "IN1")
		(8 "In3.Cu" signal "GND1")
		(10 "In4.Cu" signal "IN2")
		(12 "In5.Cu" signal "GND2")
		(14 "In6.Cu" signal "IN3")
		(16 "In7.Cu" signal "GND3")
		(18 "In8.Cu" signal "VCC")
		(20 "In9.Cu" signal "VCC1")
		(22 "In10.Cu" signal "GND4")
		(24 "In11.Cu" signal "IN4")
		(26 "In12.Cu" signal "GND5")
		(28 "In13.Cu" signal "IN5")
		(30 "In14.Cu" signal "GND6")
		(32 "In15.Cu" signal "IN6")
		(34 "In16.Cu" signal "GND7")
		(2 "B.Cu" signal "BOTTOM")
		(9 "F.Adhes" user "F.Adhesive")
		(11 "B.Adhes" user "B.Adhesive")
		(13 "F.Paste" user "Package Geometry/Pastemask Top")
		(15 "B.Paste" user "Package Geometry/Pastemask Bottom")
		(5 "F.SilkS" user "Ref Des/Silkscreen Top")
		(7 "B.SilkS" user "Ref Des/Silkscreen Bottom")
		(1 "F.Mask" user "Board Geometry/Soldermask Top")
		(3 "B.Mask" user "Board Geometry/Soldermask Bottom")
		(17 "Dwgs.User" user "User.Drawings")
		(19 "Cmts.User" user "User.Comments")
		(21 "Eco1.User" user "User.Eco1")
		(23 "Eco2.User" user "User.Eco2")
		(25 "Edge.Cuts" user "Board Geometry/Outline")
		(27 "Margin" user)
		(31 "F.CrtYd" user "Package Geometry/Place Bound Top")
		(29 "B.CrtYd" user "Package Geometry/Place Bound Bottom")
		(35 "F.Fab" user "Ref Des/Assembly Top")
		(33 "B.Fab" user "Ref Des/Assembly Bottom")
	)
	(footprint ""
		(layer "F.Cu")
		(at 343.646252 -338.86013)
		(property "Reference" "PR151"
			(at 0 0 0)
			(layer "F.SilkS")
			(hide yes)
			(effects
				(font
					(size 1.27 1.27)
				)
			)
		)
		(property "Value" ""
			(at 0 0 0)
			(layer "F.Fab")
			(effects
				(font
					(size 1.27 1.27)
				)
			)
		)
		(duplicate_pad_numbers_are_jumpers no)
		(fp_line
			(start -0.7874 -0.4064)
			(end 0.7874 -0.4064)
			(stroke
				(width 0.1524)
				(type default)
			)
			(layer "F.SilkS")
		)
		(fp_line
			(start -0.7874 0.4064)
			(end -0.7874 -0.4064)
			(stroke
				(width 0.1524)
				(type default)
			)
			(layer "F.SilkS")
		)
		(fp_line
			(start 0.7874 -0.4064)
			(end 0.7874 0.4064)
			(stroke
				(width 0.1524)
				(type default)
			)
			(layer "F.SilkS")
		)
		(fp_line
			(start 0.7874 0.4064)
			(end -0.7874 0.4064)
			(stroke
				(width 0.1524)
				(type default)
			)
			(layer "F.SilkS")
		)
		(fp_line
			(start -0.67945 -0.305054)
			(end -0.12065 -0.305054)
			(stroke
				(width 0.1)
				(type default)
			)
			(layer "F.Fab")
		)
		(fp_line
			(start -0.67945 0.3048)
			(end -0.67945 -0.305054)
			(stroke
				(width 0.1)
				(type default)
			)
			(layer "F.Fab")
		)
		(fp_line
			(start -0.12065 -0.305054)
			(end -0.12065 -0.2794)
			(stroke
				(width 0.1)
				(type default)
			)
			(layer "F.Fab")
		)
		(fp_line
			(start -0.12065 -0.2794)
			(end 0.12065 -0.2794)
			(stroke
				(width 0.1)
				(type default)
			)
			(layer "F.Fab")
		)
		(fp_line
			(start -0.12065 0.2794)
			(end -0.12065 0.3048)
			(stroke
				(width 0.1)
				(type default)
			)
			(layer "F.Fab")
		)
		(fp_line
			(start -0.12065 0.3048)
			(end -0.67945 0.3048)
			(stroke
				(width 0.1)
				(type default)
			)
			(layer "F.Fab")
		)
		(fp_line
			(start 0.120396 0.2794)
			(end -0.12065 0.2794)
			(stroke
				(width 0.1)
				(type default)
			)
			(layer "F.Fab")
		)
		(fp_line
			(start 0.120396 0.3048)
			(end 0.120396 0.2794)
			(stroke
				(width 0.1)
				(type default)
			)
			(layer "F.Fab")
		)
		(fp_line
			(start 0.12065 -0.3048)
			(end 0.67945 -0.3048)
			(stroke
				(width 0.1)
				(type default)
			)
			(layer "F.Fab")
		)
		(fp_line
			(start 0.12065 -0.2794)
			(end 0.12065 -0.3048)
			(stroke
				(width 0.1)
				(type default)
			)
			(layer "F.Fab")
		)
		(fp_line
			(start 0.67945 -0.3048)
			(end 0.67945 0.3048)
			(stroke
				(width 0.1)
				(type default)
			)
			(layer "F.Fab")
		)
		(fp_line
			(start 0.67945 0.3048)
			(end 0.120396 0.3048)
			(stroke
				(width 0.1)
				(type default)
			)
			(layer "F.Fab")
		)
		(pad "1" smd circle
			(at -0.40005 0)
			(size 0 0)
			(layers "F.Cu" "F.Mask" "F.Paste")
			(net "PVCCIN_CPU0_LSET1")
		)
		(pad "2" smd circle
			(at 0.40005 0)
			(size 0 0)
			(layers "F.Cu" "F.Mask" "F.Paste")
			(net "GND")
		)
	)
	(footprint ""
		(layer "F.Cu")
		(at 157.061408 -44.662598 90)
		(property "Reference" "R4455"
			(at 0 0 90)
			(layer "F.SilkS")
			(hide yes)
			(effects
				(font
					(size 1.27 1.27)
				)
			)
		)
		(property "Value" ""
			(at 0 0 90)
			(layer "F.Fab")
			(effects
				(font
					(size 1.27 1.27)
				)
			)
		)
		(duplicate_pad_numbers_are_jumpers no)
		(fp_line
			(start 0.7874 -0.4064)
			(end 0.7874 0.4064)
			(stroke
				(width 0.1524)
				(type default)
			)
			(layer "F.SilkS")
		)
		(fp_line
			(start 0.7874 0.4064)
			(end -0.7874 0.4064)
			(stroke
				(width 0.1524)
				(type default)
			)
			(layer "F.SilkS")
		)
		(fp_line
			(start -0.12065 -0.305054)
			(end -0.12065 -0.2794)
			(stroke
				(width 0.1)
				(type default)
			)
			(layer "F.Fab")
		)
		(fp_line
			(start -0.67945 -0.305054)
			(end -0.12065 -0.305054)
			(stroke
				(width 0.1)
				(type default)
			)
			(layer "F.Fab")
		)
		(fp_line
			(start 0.67945 -0.3048)
			(end 0.67945 0.3048)
			(stroke
				(width 0.1)
				(type default)
			)
			(layer "F.Fab")
		)
		(fp_line
			(start 0.12065 -0.3048)
			(end 0.67945 -0.3048)
			(stroke
				(width 0.1)
				(type default)
			)
			(layer "F.Fab")
		)
		(fp_line
			(start 0.12065 -0.2794)
			(end 0.12065 -0.3048)
			(stroke
				(width 0.1)
				(type default)
			)
			(layer "F.Fab")
		)
		(fp_line
			(start -0.12065 -0.2794)
			(end 0.12065 -0.2794)
			(stroke
				(width 0.1)
				(type default)
			)
			(layer "F.Fab")
		)
		(fp_line
			(start 0.120396 0.2794)
			(end -0.12065 0.2794)
			(stroke
				(width 0.1)
				(type default)
			)
			(layer "F.Fab")
		)
		(fp_line
			(start -0.12065 0.2794)
			(end -0.12065 0.3048)
			(stroke
				(width 0.1)
				(type default)
			)
			(layer "F.Fab")
		)
		(fp_line
			(start 0.67945 0.3048)
			(end 0.120396 0.3048)
			(stroke
				(width 0.1)
				(type default)
			)
			(layer "F.Fab")
		)
		(fp_line
			(start 0.120396 0.3048)
			(end 0.120396 0.2794)
			(stroke
				(width 0.1)
				(type default)
			)
			(layer "F.Fab")
		)
		(fp_line
			(start -0.12065 0.3048)
			(end -0.67945 0.3048)
			(stroke
				(width 0.1)
				(type default)
			)
			(layer "F.Fab")
		)
		(fp_line
			(start -0.67945 0.3048)
			(end -0.67945 -0.305054)
			(stroke
				(width 0.1)
				(type default)
			)
			(layer "F.Fab")
		)
		(pad "1" smd rect
			(at -0.40005 0 270)
			(size 0.4572 0.508)
			(layers "F.Cu" "F.Mask" "F.Paste")
			(net "USB2_HUB_2_EXT_DN")
		)
		(pad "2" smd rect
			(at 0.40005 0 270)
			(size 0.4572 0.508)
			(layers "F.Cu" "F.Mask" "F.Paste")
			(net "USB2_HUB_2_BUF_EXT_R_DN")
		)
	)
	(footprint ""
		(layer "F.Cu")
		(at 334.024732 -341.707978 -90)
		(property "Reference" "PC1342"
			(at 0 0 270)
			(layer "F.SilkS")
			(hide yes)
			(effects
				(font
					(size 1.27 1.27)
				)
			)
		)
		(property "Value" ""
			(at 0 0 270)
			(layer "F.Fab")
			(effects
				(font
					(size 1.27 1.27)
				)
			)
		)
		(duplicate_pad_numbers_are_jumpers no)
		(fp_line
			(start -0.7874 0.4064)
			(end -0.7874 -0.4064)
			(stroke
				(width 0.1524)
				(type default)
			)
			(layer "F.SilkS")
		)
		(fp_line
			(start 0.7874 0.4064)
			(end -0.7874 0.4064)
			(stroke
				(width 0.1524)
				(type default)
			)
			(layer "F.SilkS")
		)
		(fp_line
			(start -0.7874 -0.4064)
			(end 0.7874 -0.4064)
			(stroke
				(width 0.1524)
				(type default)
			)
			(layer "F.SilkS")
		)
		(fp_line
			(start 0.7874 -0.4064)
			(end 0.7874 0.4064)
			(stroke
				(width 0.1524)
				(type default)
			)
			(layer "F.SilkS")
		)
		(fp_line
			(start -0.67945 0.3048)
			(end -0.67945 -0.305054)
			(stroke
				(width 0.1)
				(type default)
			)
			(layer "F.Fab")
		)
		(fp_line
			(start -0.12065 0.3048)
			(end -0.67945 0.3048)
			(stroke
				(width 0.1)
				(type default)
			)
			(layer "F.Fab")
		)
		(fp_line
			(start 0.120396 0.3048)
			(end 0.120396 0.2794)
			(stroke
				(width 0.1)
				(type default)
			)
			(layer "F.Fab")
		)
		(fp_line
			(start 0.67945 0.3048)
			(end 0.120396 0.3048)
			(stroke
				(width 0.1)
				(type default)
			)
			(layer "F.Fab")
		)
		(fp_line
			(start -0.12065 0.2794)
			(end -0.12065 0.3048)
			(stroke
				(width 0.1)
				(type default)
			)
			(layer "F.Fab")
		)
		(fp_line
			(start 0.120396 0.2794)
			(end -0.12065 0.2794)
			(stroke
				(width 0.1)
				(type default)
			)
			(layer "F.Fab")
		)
		(fp_line
			(start -0.12065 -0.2794)
			(end 0.12065 -0.2794)
			(stroke
				(width 0.1)
				(type default)
			)
			(layer "F.Fab")
		)
		(fp_line
			(start 0.12065 -0.2794)
			(end 0.12065 -0.3048)
			(stroke
				(width 0.1)
				(type default)
			)
			(layer "F.Fab")
		)
		(fp_line
			(start 0.12065 -0.3048)
			(end 0.67945 -0.3048)
			(stroke
				(width 0.1)
				(type default)
			)
			(layer "F.Fab")
		)
		(fp_line
			(start 0.67945 -0.3048)
			(end 0.67945 0.3048)
			(stroke
				(width 0.1)
				(type default)
			)
			(layer "F.Fab")
		)
		(fp_line
			(start -0.67945 -0.305054)
			(end -0.12065 -0.305054)
			(stroke
				(width 0.1)
				(type default)
			)
			(layer "F.Fab")
		)
		(fp_line
			(start -0.12065 -0.305054)
			(end -0.12065 -0.2794)
			(stroke
				(width 0.1)
				(type default)
			)
			(layer "F.Fab")
		)
		(pad "1" smd circle
			(at -0.40005 0 270)
			(size 0 0)
			(layers "F.Cu" "F.Mask" "F.Paste")
			(net "GND")
		)
		(pad "2" smd circle
			(at 0.40005 0 270)
			(size 0 0)
			(layers "F.Cu" "F.Mask" "F.Paste")
			(net "PVCCIN_CPU0_VREF")
		)
	)
	(footprint ""
		(layer "F.Cu")
		(at 294.899588 -365.251746 90)
		(property "Reference" "PC601"
			(at 0 0 90)
			(layer "F.SilkS")
			(hide yes)
			(effects
				(font
					(size 1.27 1.27)
				)
			)
		)
		(property "Value" ""
			(at 0 0 90)
			(layer "F.Fab")
			(effects
				(font
					(size 1.27 1.27)
				)
			)
		)
		(duplicate_pad_numbers_are_jumpers no)
		(fp_line
			(start 0.7874 -0.4064)
			(end 0.7874 0.4064)
			(stroke
				(width 0.1524)
				(type default)
			)
			(layer "F.SilkS")
		)
		(fp_line
			(start -0.7874 -0.4064)
			(end 0.7874 -0.4064)
			(stroke
				(width 0.1524)
				(type default)
			)
			(layer "F.SilkS")
		)
		(fp_line
			(start 0.7874 0.4064)
			(end -0.7874 0.4064)
			(stroke
				(width 0.1524)
				(type default)
			)
			(layer "F.SilkS")
		)
		(fp_line
			(start -0.7874 0.4064)
			(end -0.7874 -0.4064)
			(stroke
				(width 0.1524)
				(type default)
			)
			(layer "F.SilkS")
		)
		(fp_line
			(start -0.12065 -0.305054)
			(end -0.12065 -0.2794)
			(stroke
				(width 0.1)
				(type default)
			)
			(layer "F.Fab")
		)
		(fp_line
			(start -0.67945 -0.305054)
			(end -0.12065 -0.305054)
			(stroke
				(width 0.1)
				(type default)
			)
			(layer "F.Fab")
		)
		(fp_line
			(start 0.67945 -0.3048)
			(end 0.67945 0.3048)
			(stroke
				(width 0.1)
				(type default)
			)
			(layer "F.Fab")
		)
		(fp_line
			(start 0.12065 -0.3048)
			(end 0.67945 -0.3048)
			(stroke
				(width 0.1)
				(type default)
			)
			(layer "F.Fab")
		)
		(fp_line
			(start 0.12065 -0.2794)
			(end 0.12065 -0.3048)
			(stroke
				(width 0.1)
				(type default)
			)
			(layer "F.Fab")
		)
		(fp_line
			(start -0.12065 -0.2794)
			(end 0.12065 -0.2794)
			(stroke
				(width 0.1)
				(type default)
			)
			(layer "F.Fab")
		)
		(fp_line
			(start 0.120396 0.2794)
			(end -0.12065 0.2794)
			(stroke
				(width 0.1)
				(type default)
			)
			(layer "F.Fab")
		)
		(fp_line
			(start -0.12065 0.2794)
			(end -0.12065 0.3048)
			(stroke
				(width 0.1)
				(type default)
			)
			(layer "F.Fab")
		)
		(fp_line
			(start 0.67945 0.3048)
			(end 0.120396 0.3048)
			(stroke
				(width 0.1)
				(type default)
			)
			(layer "F.Fab")
		)
		(fp_line
			(start 0.120396 0.3048)
			(end 0.120396 0.2794)
			(stroke
				(width 0.1)
				(type default)
			)
			(layer "F.Fab")
		)
		(fp_line
			(start -0.12065 0.3048)
			(end -0.67945 0.3048)
			(stroke
				(width 0.1)
				(type default)
			)
			(layer "F.Fab")
		)
		(fp_line
			(start -0.67945 0.3048)
			(end -0.67945 -0.305054)
			(stroke
				(width 0.1)
				(type default)
			)
			(layer "F.Fab")
		)
		(pad "1" smd circle
			(at -0.40005 0 90)
			(size 0 0)
			(layers "F.Cu" "F.Mask" "F.Paste")
			(net "PVCCFA_EHV_FIVRA_CPU0_VDD2")
		)
		(pad "2" smd circle
			(at 0.40005 0 90)
			(size 0 0)
			(layers "F.Cu" "F.Mask" "F.Paste")
			(net "GND")
		)
	)
	(footprint ""
		(layer "F.Cu")
		(at 295.548304 -426.478446 -90)
		(property "Reference" "R4155"
			(at 0 0 270)
			(layer "F.SilkS")
			(hide yes)
			(effects
				(font
					(size 1.27 1.27)
				)
			)
		)
		(property "Value" ""
			(at 0 0 270)
			(layer "F.Fab")
			(effects
				(font
					(size 1.27 1.27)
				)
			)
		)
		(duplicate_pad_numbers_are_jumpers no)
		(fp_line
			(start -0.7874 0.4064)
			(end -0.7874 -0.4064)
			(stroke
				(width 0.1524)
				(type default)
			)
			(layer "F.SilkS")
		)
		(fp_line
			(start 0.7874 0.4064)
			(end -0.7874 0.4064)
			(stroke
				(width 0.1524)
				(type default)
			)
			(layer "F.SilkS")
		)
		(fp_line
			(start -0.7874 -0.4064)
			(end 0.7874 -0.4064)
			(stroke
				(width 0.1524)
				(type default)
			)
			(layer "F.SilkS")
		)
		(fp_line
			(start 0.7874 -0.4064)
			(end 0.7874 0.4064)
			(stroke
				(width 0.1524)
				(type default)
			)
			(layer "F.SilkS")
		)
		(fp_line
			(start -0.67945 0.3048)
			(end -0.67945 -0.305054)
			(stroke
				(width 0.1)
				(type default)
			)
			(layer "F.Fab")
		)
		(fp_line
			(start -0.12065 0.3048)
			(end -0.67945 0.3048)
			(stroke
				(width 0.1)
				(type default)
			)
			(layer "F.Fab")
		)
		(fp_line
			(start 0.120396 0.3048)
			(end 0.120396 0.2794)
			(stroke
				(width 0.1)
				(type default)
			)
			(layer "F.Fab")
		)
		(fp_line
			(start 0.67945 0.3048)
			(end 0.120396 0.3048)
			(stroke
				(width 0.1)
				(type default)
			)
			(layer "F.Fab")
		)
		(fp_line
			(start -0.12065 0.2794)
			(end -0.12065 0.3048)
			(stroke
				(width 0.1)
				(type default)
			)
			(layer "F.Fab")
		)
		(fp_line
			(start 0.120396 0.2794)
			(end -0.12065 0.2794)
			(stroke
				(width 0.1)
				(type default)
			)
			(layer "F.Fab")
		)
		(fp_line
			(start -0.12065 -0.2794)
			(end 0.12065 -0.2794)
			(stroke
				(width 0.1)
				(type default)
			)
			(layer "F.Fab")
		)
		(fp_line
			(start 0.12065 -0.2794)
			(end 0.12065 -0.3048)
			(stroke
				(width 0.1)
				(type default)
			)
			(layer "F.Fab")
		)
		(fp_line
			(start 0.12065 -0.3048)
			(end 0.67945 -0.3048)
			(stroke
				(width 0.1)
				(type default)
			)
			(layer "F.Fab")
		)
		(fp_line
			(start 0.67945 -0.3048)
			(end 0.67945 0.3048)
			(stroke
				(width 0.1)
				(type default)
			)
			(layer "F.Fab")
		)
		(fp_line
			(start -0.67945 -0.305054)
			(end -0.12065 -0.305054)
			(stroke
				(width 0.1)
				(type default)
			)
			(layer "F.Fab")
		)
		(fp_line
			(start -0.12065 -0.305054)
			(end -0.12065 -0.2794)
			(stroke
				(width 0.1)
				(type default)
			)
			(layer "F.Fab")
		)
		(pad "1" smd circle
			(at -0.40005 0 270)
			(size 0 0)
			(layers "F.Cu" "F.Mask" "F.Paste")
			(net "P3V3_AUX")
		)
		(pad "2" smd circle
			(at 0.40005 0 270)
			(size 0 0)
			(layers "F.Cu" "F.Mask" "F.Paste")
			(net "PRSNT_CABLE_GPU_A1")
		)
	)
	(footprint ""
		(layer "F.Cu")
		(at 164.211 -125.73 180)
		(property "Reference" "U324"
			(at -3.07721 -2.33426 90)
			(unlocked yes)
			(layer "F.SilkS")
			(effects
				(font
					(size 0.7874 0.5842)
					(thickness 0.1524)
				)
				(justify left)
			)
		)
		(property "Value" ""
			(at 0 0 180)
			(layer "F.Fab")
			(effects
				(font
					(size 1.27 1.27)
				)
			)
		)
		(duplicate_pad_numbers_are_jumpers no)
		(fp_line
			(start 1.603248 1.500124)
			(end -1.603248 1.500124)
			(stroke
				(width 0.1524)
				(type default)
			)
			(layer "F.SilkS")
		)
		(fp_line
			(start 1.603248 -1.500124)
			(end 1.603248 1.500124)
			(stroke
				(width 0.1524)
				(type default)
			)
			(layer "F.SilkS")
		)
		(fp_line
			(start -1.603248 1.500124)
			(end -1.603248 -1.500124)
			(stroke
				(width 0.1524)
				(type default)
			)
			(layer "F.SilkS")
		)
		(fp_line
			(start -1.603248 -1.500124)
			(end 1.603248 -1.500124)
			(stroke
				(width 0.1524)
				(type default)
			)
			(layer "F.SilkS")
		)
		(fp_line
			(start 1.249934 0.219964)
			(end 1.249934 -0.219964)
			(stroke
				(width 0.1)
				(type default)
			)
			(layer "F.Fab")
		)
		(fp_line
			(start 1.249934 -0.219964)
			(end 0.700024 -0.219964)
			(stroke
				(width 0.1)
				(type default)
			)
			(layer "F.Fab")
		)
		(fp_line
			(start 0.700024 1.500124)
			(end 0.700024 0.219964)
			(stroke
				(width 0.1)
				(type default)
			)
			(layer "F.Fab")
		)
		(fp_line
			(start 0.700024 0.219964)
			(end 1.249934 0.219964)
			(stroke
				(width 0.1)
				(type default)
			)
			(layer "F.Fab")
		)
		(fp_line
			(start 0.700024 -0.219964)
			(end 0.700024 -1.500124)
			(stroke
				(width 0.1)
				(type default)
			)
			(layer "F.Fab")
		)
		(fp_line
			(start 0.700024 -1.500124)
			(end -0.700024 -1.500124)
			(stroke
				(width 0.1)
				(type default)
			)
			(layer "F.Fab")
		)
		(fp_line
			(start -0.6985 0.729996)
			(end -1.249934 0.729996)
			(stroke
				(width 0.1)
				(type default)
			)
			(layer "F.Fab")
		)
		(fp_line
			(start -0.6985 -0.729996)
			(end -0.6985 0.729996)
			(stroke
				(width 0.1)
				(type default)
			)
			(layer "F.Fab")
		)
		(fp_line
			(start -0.700024 1.500124)
			(end 0.700024 1.500124)
			(stroke
				(width 0.1)
				(type default)
			)
			(layer "F.Fab")
		)
		(fp_line
			(start -0.700024 1.169924)
			(end -0.700024 1.500124)
			(stroke
				(width 0.1)
				(type default)
			)
			(layer "F.Fab")
		)
		(fp_line
			(start -0.700024 -1.169924)
			(end -1.249934 -1.169924)
			(stroke
				(width 0.1)
				(type default)
			)
			(layer "F.Fab")
		)
		(fp_line
			(start -0.700024 -1.500124)
			(end -0.700024 -1.169924)
			(stroke
				(width 0.1)
				(type default)
			)
			(layer "F.Fab")
		)
		(fp_line
			(start -1.249934 1.169924)
			(end -0.700024 1.169924)
			(stroke
				(width 0.1)
				(type default)
			)
			(layer "F.Fab")
		)
		(fp_line
			(start -1.249934 0.729996)
			(end -1.249934 1.169924)
			(stroke
				(width 0.1)
				(type default)
			)
			(layer "F.Fab")
		)
		(fp_line
			(start -1.249934 -0.729996)
			(end -0.6985 -0.729996)
			(stroke
				(width 0.1)
				(type default)
			)
			(layer "F.Fab")
		)
		(fp_line
			(start -1.249934 -1.169924)
			(end -1.249934 -0.729996)
			(stroke
				(width 0.1)
				(type default)
			)
			(layer "F.Fab")
		)
		(fp_rect
			(start -0.700024 1.500124)
			(end 0.700024 -1.500124)
			(stroke
				(width 0)
				(type default)
			)
			(fill no)
			(layer "F.Fab")
		)
		(pad "D" smd rect
			(at 0.999998 0 90)
			(size 0.8128 0.9144)
			(layers "F.Cu" "F.Mask" "F.Paste")
			(net "VR_P5V_EN_D")
		)
		(pad "G" smd rect
			(at -0.999998 -0.94996 90)
			(size 0.8128 0.9144)
			(layers "F.Cu" "F.Mask" "F.Paste")
			(net "VR_P5V_EN_N")
		)
		(pad "S" smd rect
			(at -0.999998 0.94996 90)
			(size 0.8128 0.9144)
			(layers "F.Cu" "F.Mask" "F.Paste")
			(net "GND")
		)
	)
)
